# SCM (Grand Teton) — schematic netlist excerpt (pin names and nets, part order shuffled) for the footprints in the layout excerpt that follows; sources: Cadence DE-HDL packaged netlist, KiCad conversion of 12092022_DA0F0TMDCD0_F0T_Management_Board_D_brd_V3_OCP.brd

R687  Q_RES  4.7K 1% EMPTY  pkg 0402LF  page 14 : A = P3V3_AUX ; B = BMC_EMMC_CD_N
C42  Q_CAP  22UF 6.3V 20% X6S  pkg C0603  page 15 : A = PVCCIO_PECI_BMC ; B = GND

(kicad_pcb
	(version 20260206)
	(generator "pcbnew")
	(generator_version "10.0")
	(general
		(thickness 1.6)
		(legacy_teardrops no)
	)
	(paper "A4")
	(title_block
		(title "12092022_DA0F0TMDCD0_F0T_Management_Board_D_brd_V3_OCP.brd")
		(comment 1 "Grand Teton / footprints 885-886 of 1440")
	)
	(layers
		(0 "F.Cu" signal "TOP")
		(4 "In1.Cu" signal "GND")
		(6 "In2.Cu" signal "IN1")
		(8 "In3.Cu" signal "GND1")
		(10 "In4.Cu" signal "IN2")
		(12 "In5.Cu" signal "VCC")
		(14 "In6.Cu" signal "VCC1")
		(16 "In7.Cu" signal "IN3")
		(18 "In8.Cu" signal "GND2")
		(20 "In9.Cu" signal "IN4")
		(22 "In10.Cu" signal "GND3")
		(2 "B.Cu" signal "BOTTOM")
		(9 "F.Adhes" user "F.Adhesive")
		(11 "B.Adhes" user "B.Adhesive")
		(13 "F.Paste" user "Package Geometry/Pastemask Top")
		(15 "B.Paste" user "Package Geometry/Pastemask Bottom")
		(5 "F.SilkS" user "Ref Des/Silkscreen Top")
		(7 "B.SilkS" user "Ref Des/Silkscreen Bottom")
		(1 "F.Mask" user "Board Geometry/Soldermask Top")
		(3 "B.Mask" user "Board Geometry/Soldermask Bottom")
		(17 "Dwgs.User" user "User.Drawings")
		(19 "Cmts.User" user "User.Comments")
		(21 "Eco1.User" user "User.Eco1")
		(23 "Eco2.User" user "User.Eco2")
		(25 "Edge.Cuts" user "Board Geometry/Outline")
		(27 "Margin" user)
		(31 "F.CrtYd" user "Package Geometry/Place Bound Top")
		(29 "B.CrtYd" user "Package Geometry/Place Bound Bottom")
		(35 "F.Fab" user "Ref Des/Assembly Top")
		(33 "B.Fab" user "Ref Des/Assembly Bottom")
	)
	(footprint ""
		(layer "B.Cu")
		(at 71.599806 -69.576188 -90)
		(property "Reference" "R687"
			(at 0 0 90)
			(layer "B.SilkS")
			(hide yes)
			(effects
				(font
					(size 1.27 1.27)
				)
				(justify mirror)
			)
		)
		(property "Value" ""
			(at 0 0 90)
			(layer "B.Fab")
			(effects
				(font
					(size 1.27 1.27)
				)
				(justify mirror)
			)
		)
		(duplicate_pad_numbers_are_jumpers no)
		(fp_line
			(start -0.7874 0.4064)
			(end 0.7874 0.4064)
			(stroke
				(width 0.1524)
				(type default)
			)
			(layer "B.SilkS")
		)
		(fp_line
			(start 0.7874 0.4064)
			(end 0.7874 -0.4064)
			(stroke
				(width 0.1524)
				(type default)
			)
			(layer "B.SilkS")
		)
		(fp_line
			(start -0.7874 -0.4064)
			(end -0.7874 0.4064)
			(stroke
				(width 0.1524)
				(type default)
			)
			(layer "B.SilkS")
		)
		(fp_line
			(start 0.7874 -0.4064)
			(end -0.7874 -0.4064)
			(stroke
				(width 0.1524)
				(type default)
			)
			(layer "B.SilkS")
		)
		(fp_line
			(start -0.67945 0.3048)
			(end -0.120396 0.3048)
			(stroke
				(width 0.1)
				(type default)
			)
			(layer "B.Fab")
		)
		(fp_line
			(start -0.120396 0.3048)
			(end -0.120396 0.2794)
			(stroke
				(width 0.1)
				(type default)
			)
			(layer "B.Fab")
		)
		(fp_line
			(start 0.12065 0.3048)
			(end 0.67945 0.3048)
			(stroke
				(width 0.1)
				(type default)
			)
			(layer "B.Fab")
		)
		(fp_line
			(start 0.67945 0.3048)
			(end 0.67945 -0.305054)
			(stroke
				(width 0.1)
				(type default)
			)
			(layer "B.Fab")
		)
		(fp_line
			(start -0.120396 0.2794)
			(end 0.12065 0.2794)
			(stroke
				(width 0.1)
				(type default)
			)
			(layer "B.Fab")
		)
		(fp_line
			(start 0.12065 0.2794)
			(end 0.12065 0.3048)
			(stroke
				(width 0.1)
				(type default)
			)
			(layer "B.Fab")
		)
		(fp_line
			(start -0.12065 -0.2794)
			(end -0.12065 -0.3048)
			(stroke
				(width 0.1)
				(type default)
			)
			(layer "B.Fab")
		)
		(fp_line
			(start 0.12065 -0.2794)
			(end -0.12065 -0.2794)
			(stroke
				(width 0.1)
				(type default)
			)
			(layer "B.Fab")
		)
		(fp_line
			(start -0.67945 -0.3048)
			(end -0.67945 0.3048)
			(stroke
				(width 0.1)
				(type default)
			)
			(layer "B.Fab")
		)
		(fp_line
			(start -0.12065 -0.3048)
			(end -0.67945 -0.3048)
			(stroke
				(width 0.1)
				(type default)
			)
			(layer "B.Fab")
		)
		(fp_line
			(start 0.12065 -0.305054)
			(end 0.12065 -0.2794)
			(stroke
				(width 0.1)
				(type default)
			)
			(layer "B.Fab")
		)
		(fp_line
			(start 0.67945 -0.305054)
			(end 0.12065 -0.305054)
			(stroke
				(width 0.1)
				(type default)
			)
			(layer "B.Fab")
		)
		(pad "1" smd circle
			(at 0.40005 0 90)
			(size 0 0)
			(layers "B.Cu" "B.Mask" "B.Paste")
			(net "P3V3_AUX")
		)
		(pad "2" smd circle
			(at -0.40005 0 90)
			(size 0 0)
			(layers "B.Cu" "B.Mask" "B.Paste")
			(net "BMC_EMMC_CD_N")
		)
	)
	(footprint ""
		(layer "B.Cu")
		(at 38.518592 -56.120538)
		(property "Reference" "C42"
			(at 0 0 0)
			(layer "B.SilkS")
			(hide yes)
			(effects
				(font
					(size 1.27 1.27)
				)
				(justify mirror)
			)
		)
		(property "Value" ""
			(at 0 0 0)
			(layer "B.Fab")
			(effects
				(font
					(size 1.27 1.27)
				)
				(justify mirror)
			)
		)
		(duplicate_pad_numbers_are_jumpers no)
		(fp_line
			(start -1.2954 -0.5842)
			(end -1.2954 0.5842)
			(stroke
				(width 0.1524)
				(type default)
			)
			(layer "B.SilkS")
		)
		(fp_line
			(start -1.2954 0.5842)
			(end 1.2954 0.5842)
			(stroke
				(width 0.1524)
				(type default)
			)
			(layer "B.SilkS")
		)
		(fp_line
			(start 0 -0.5842)
			(end 0 0.5842)
			(stroke
				(width 0.1524)
				(type default)
			)
			(layer "B.SilkS")
		)
		(fp_line
			(start 1.2954 -0.5842)
			(end -1.2954 -0.5842)
			(stroke
				(width 0.1524)
				(type default)
			)
			(layer "B.SilkS")
		)
		(fp_line
			(start 1.2954 0.5842)
			(end 1.2954 -0.5842)
			(stroke
				(width 0.1524)
				(type default)
			)
			(layer "B.SilkS")
		)
		(fp_line
			(start -1.1938 -0.4064)
			(end -1.1938 0.4064)
			(stroke
				(width 0.1)
				(type default)
			)
			(layer "B.Fab")
		)
		(fp_line
			(start -1.1938 0.4064)
			(end -0.8636 0.4064)
			(stroke
				(width 0.1)
				(type default)
			)
			(layer "B.Fab")
		)
		(fp_line
			(start -0.8636 -0.4572)
			(end -0.8636 -0.4064)
			(stroke
				(width 0.1)
				(type default)
			)
			(layer "B.Fab")
		)
		(fp_line
			(start -0.8636 -0.4064)
			(end -1.1938 -0.4064)
			(stroke
				(width 0.1)
				(type default)
			)
			(layer "B.Fab")
		)
		(fp_line
			(start -0.8636 0.4064)
			(end -0.8636 0.4572)
			(stroke
				(width 0.1)
				(type default)
			)
			(layer "B.Fab")
		)
		(fp_line
			(start -0.8636 0.4572)
			(end 0.8636 0.4572)
			(stroke
				(width 0.1)
				(type default)
			)
			(layer "B.Fab")
		)
		(fp_line
			(start 0.8636 -0.4572)
			(end -0.8636 -0.4572)
			(stroke
				(width 0.1)
				(type default)
			)
			(layer "B.Fab")
		)
		(fp_line
			(start 0.8636 -0.4064)
			(end 0.8636 -0.4572)
			(stroke
				(width 0.1)
				(type default)
			)
			(layer "B.Fab")
		)
		(fp_line
			(start 0.8636 0.4064)
			(end 1.1938 0.4064)
			(stroke
				(width 0.1)
				(type default)
			)
			(layer "B.Fab")
		)
		(fp_line
			(start 0.8636 0.4572)
			(end 0.8636 0.4064)
			(stroke
				(width 0.1)
				(type default)
			)
			(layer "B.Fab")
		)
		(fp_line
			(start 1.1938 -0.4064)
			(end 0.8636 -0.4064)
			(stroke
				(width 0.1)
				(type default)
			)
			(layer "B.Fab")
		)
		(fp_line
			(start 1.1938 0.4064)
			(end 1.1938 -0.4064)
			(stroke
				(width 0.1)
				(type default)
			)
			(layer "B.Fab")
		)
		(pad "1" smd rect
			(at 0.7366 0 270)
			(size 0.7112 0.8128)
			(layers "B.Cu" "B.Mask" "B.Paste")
			(net "PVCCIO_PECI_BMC")
		)
		(pad "2" smd rect
			(at -0.7366 0 270)
			(size 0.7112 0.8128)
			(layers "B.Cu" "B.Mask" "B.Paste")
			(net "GND")
		)
	)
)
